(kicad_pcb
	(version 20260206)
	(generator "pcbnew")
	(generator_version "10.0")
	(general
		(thickness 1.6)
		(legacy_teardrops no)
	)
	(paper "A4")
	(title_block
		(title "03242023_DA0F0TMBIJ0_F0T_Motherboard_J_brd_V01_OCP.brd")
		(comment 1 "Grand Teton / footprints 556-561 of 6105")
	)
	(layers
		(0 "F.Cu" signal "TOP")
		(4 "In1.Cu" signal "GND")
		(6 "In2.Cu" signal "IN1")
		(8 "In3.Cu" signal "GND1")
		(10 "In4.Cu" signal "IN2")
		(12 "In5.Cu" signal "GND2")
		(14 "In6.Cu" signal "IN3")
		(16 "In7.Cu" signal "GND3")
		(18 "In8.Cu" signal "VCC")
		(20 "In9.Cu" signal "VCC1")
		(22 "In10.Cu" signal "GND4")
		(24 "In11.Cu" signal "IN4")
		(26 "In12.Cu" signal "GND5")
		(28 "In13.Cu" signal "IN5")
		(30 "In14.Cu" signal "GND6")
		(32 "In15.Cu" signal "IN6")
		(34 "In16.Cu" signal "GND7")
		(2 "B.Cu" signal "BOTTOM")
		(9 "F.Adhes" user "F.Adhesive")
		(11 "B.Adhes" user "B.Adhesive")
		(13 "F.Paste" user "Package Geometry/Pastemask Top")
		(15 "B.Paste" user "Package Geometry/Pastemask Bottom")
		(5 "F.SilkS" user "Ref Des/Silkscreen Top")
		(7 "B.SilkS" user "Ref Des/Silkscreen Bottom")
		(1 "F.Mask" user "Board Geometry/Soldermask Top")
		(3 "B.Mask" user "Board Geometry/Soldermask Bottom")
		(17 "Dwgs.User" user "User.Drawings")
		(19 "Cmts.User" user "User.Comments")
		(21 "Eco1.User" user "User.Eco1")
		(23 "Eco2.User" user "User.Eco2")
		(25 "Edge.Cuts" user "Board Geometry/Outline")
		(27 "Margin" user)
		(31 "F.CrtYd" user "Package Geometry/Place Bound Top")
		(29 "B.CrtYd" user "Package Geometry/Place Bound Bottom")
		(35 "F.Fab" user "Ref Des/Assembly Top")
		(33 "B.Fab" user "Ref Des/Assembly Bottom")
	)
	(footprint ""
		(layer "F.Cu")
		(at 34.177478 -439.339228 -90)
		(property "Reference" "R2987"
			(at 0 0 270)
			(layer "F.SilkS")
			(hide yes)
			(effects
				(font
					(size 1.27 1.27)
				)
			)
		)
		(property "Value" ""
			(at 0 0 270)
			(layer "F.Fab")
			(effects
				(font
					(size 1.27 1.27)
				)
			)
		)
		(duplicate_pad_numbers_are_jumpers no)
		(fp_line
			(start -0.7874 0.4064)
			(end -0.7874 -0.4064)
			(stroke
				(width 0.1524)
				(type default)
			)
			(layer "F.SilkS")
		)
		(fp_line
			(start 0.7874 0.4064)
			(end -0.7874 0.4064)
			(stroke
				(width 0.1524)
				(type default)
			)
			(layer "F.SilkS")
		)
		(fp_line
			(start -0.7874 -0.4064)
			(end 0.7874 -0.4064)
			(stroke
				(width 0.1524)
				(type default)
			)
			(layer "F.SilkS")
		)
		(fp_line
			(start 0.7874 -0.4064)
			(end 0.7874 0.4064)
			(stroke
				(width 0.1524)
				(type default)
			)
			(layer "F.SilkS")
		)
		(fp_line
			(start -0.67945 0.3048)
			(end -0.67945 -0.305054)
			(stroke
				(width 0.1)
				(type default)
			)
			(layer "F.Fab")
		)
		(fp_line
			(start -0.12065 0.3048)
			(end -0.67945 0.3048)
			(stroke
				(width 0.1)
				(type default)
			)
			(layer "F.Fab")
		)
		(fp_line
			(start 0.120396 0.3048)
			(end 0.120396 0.2794)
			(stroke
				(width 0.1)
				(type default)
			)
			(layer "F.Fab")
		)
		(fp_line
			(start 0.67945 0.3048)
			(end 0.120396 0.3048)
			(stroke
				(width 0.1)
				(type default)
			)
			(layer "F.Fab")
		)
		(fp_line
			(start -0.12065 0.2794)
			(end -0.12065 0.3048)
			(stroke
				(width 0.1)
				(type default)
			)
			(layer "F.Fab")
		)
		(fp_line
			(start 0.120396 0.2794)
			(end -0.12065 0.2794)
			(stroke
				(width 0.1)
				(type default)
			)
			(layer "F.Fab")
		)
		(fp_line
			(start -0.12065 -0.2794)
			(end 0.12065 -0.2794)
			(stroke
				(width 0.1)
				(type default)
			)
			(layer "F.Fab")
		)
		(fp_line
			(start 0.12065 -0.2794)
			(end 0.12065 -0.3048)
			(stroke
				(width 0.1)
				(type default)
			)
			(layer "F.Fab")
		)
		(fp_line
			(start 0.12065 -0.3048)
			(end 0.67945 -0.3048)
			(stroke
				(width 0.1)
				(type default)
			)
			(layer "F.Fab")
		)
		(fp_line
			(start 0.67945 -0.3048)
			(end 0.67945 0.3048)
			(stroke
				(width 0.1)
				(type default)
			)
			(layer "F.Fab")
		)
		(fp_line
			(start -0.67945 -0.305054)
			(end -0.12065 -0.305054)
			(stroke
				(width 0.1)
				(type default)
			)
			(layer "F.Fab")
		)
		(fp_line
			(start -0.12065 -0.305054)
			(end -0.12065 -0.2794)
			(stroke
				(width 0.1)
				(type default)
			)
			(layer "F.Fab")
		)
		(pad "1" smd circle
			(at -0.40005 0 270)
			(size 0 0)
			(layers "F.Cu" "F.Mask" "F.Paste")
			(net "SMB_2_BMC_GPU_R_SDA")
		)
		(pad "2" smd circle
			(at 0.40005 0 270)
			(size 0 0)
			(layers "F.Cu" "F.Mask" "F.Paste")
			(net "SMB_2_BMC_GPU_BUF_R_SDA")
		)
	)
	(footprint ""
		(layer "F.Cu")
		(at 160.782 -103.342948)
		(property "Reference" "R1751"
			(at 0 0 0)
			(layer "F.SilkS")
			(hide yes)
			(effects
				(font
					(size 1.27 1.27)
				)
			)
		)
		(property "Value" ""
			(at 0 0 0)
			(layer "F.Fab")
			(effects
				(font
					(size 1.27 1.27)
				)
			)
		)
		(duplicate_pad_numbers_are_jumpers no)
		(fp_line
			(start -0.7874 -0.4064)
			(end 0.7874 -0.4064)
			(stroke
				(width 0.1524)
				(type default)
			)
			(layer "F.SilkS")
		)
		(fp_line
			(start -0.7874 0.4064)
			(end -0.7874 -0.4064)
			(stroke
				(width 0.1524)
				(type default)
			)
			(layer "F.SilkS")
		)
		(fp_line
			(start 0.7874 -0.4064)
			(end 0.7874 0.4064)
			(stroke
				(width 0.1524)
				(type default)
			)
			(layer "F.SilkS")
		)
		(fp_line
			(start 0.7874 0.4064)
			(end -0.7874 0.4064)
			(stroke
				(width 0.1524)
				(type default)
			)
			(layer "F.SilkS")
		)
		(fp_line
			(start -0.67945 -0.305054)
			(end -0.12065 -0.305054)
			(stroke
				(width 0.1)
				(type default)
			)
			(layer "F.Fab")
		)
		(fp_line
			(start -0.67945 0.3048)
			(end -0.67945 -0.305054)
			(stroke
				(width 0.1)
				(type default)
			)
			(layer "F.Fab")
		)
		(fp_line
			(start -0.12065 -0.305054)
			(end -0.12065 -0.2794)
			(stroke
				(width 0.1)
				(type default)
			)
			(layer "F.Fab")
		)
		(fp_line
			(start -0.12065 -0.2794)
			(end 0.12065 -0.2794)
			(stroke
				(width 0.1)
				(type default)
			)
			(layer "F.Fab")
		)
		(fp_line
			(start -0.12065 0.2794)
			(end -0.12065 0.3048)
			(stroke
				(width 0.1)
				(type default)
			)
			(layer "F.Fab")
		)
		(fp_line
			(start -0.12065 0.3048)
			(end -0.67945 0.3048)
			(stroke
				(width 0.1)
				(type default)
			)
			(layer "F.Fab")
		)
		(fp_line
			(start 0.120396 0.2794)
			(end -0.12065 0.2794)
			(stroke
				(width 0.1)
				(type default)
			)
			(layer "F.Fab")
		)
		(fp_line
			(start 0.120396 0.3048)
			(end 0.120396 0.2794)
			(stroke
				(width 0.1)
				(type default)
			)
			(layer "F.Fab")
		)
		(fp_line
			(start 0.12065 -0.3048)
			(end 0.67945 -0.3048)
			(stroke
				(width 0.1)
				(type default)
			)
			(layer "F.Fab")
		)
		(fp_line
			(start 0.12065 -0.2794)
			(end 0.12065 -0.3048)
			(stroke
				(width 0.1)
				(type default)
			)
			(layer "F.Fab")
		)
		(fp_line
			(start 0.67945 -0.3048)
			(end 0.67945 0.3048)
			(stroke
				(width 0.1)
				(type default)
			)
			(layer "F.Fab")
		)
		(fp_line
			(start 0.67945 0.3048)
			(end 0.120396 0.3048)
			(stroke
				(width 0.1)
				(type default)
			)
			(layer "F.Fab")
		)
		(pad "1" smd circle
			(at -0.40005 0)
			(size 0 0)
			(layers "F.Cu" "F.Mask" "F.Paste")
			(net "SGPIO_DO_0")
		)
		(pad "2" smd circle
			(at 0.40005 0)
			(size 0 0)
			(layers "F.Cu" "F.Mask" "F.Paste")
			(net "SGPIO_DEBUG_PLD_DOUT")
		)
	)
	(footprint ""
		(layer "F.Cu")
		(at 435.997858 -106.76636 180)
		(property "Reference" "PR3798"
			(at 0 0 180)
			(layer "F.SilkS")
			(hide yes)
			(effects
				(font
					(size 1.27 1.27)
				)
			)
		)
		(property "Value" ""
			(at 0 0 180)
			(layer "F.Fab")
			(effects
				(font
					(size 1.27 1.27)
				)
			)
		)
		(duplicate_pad_numbers_are_jumpers no)
		(fp_line
			(start 0.7874 0.4064)
			(end -0.7874 0.4064)
			(stroke
				(width 0.1524)
				(type default)
			)
			(layer "F.SilkS")
		)
		(fp_line
			(start 0.7874 -0.4064)
			(end 0.7874 0.4064)
			(stroke
				(width 0.1524)
				(type default)
			)
			(layer "F.SilkS")
		)
		(fp_line
			(start -0.7874 0.4064)
			(end -0.7874 -0.4064)
			(stroke
				(width 0.1524)
				(type default)
			)
			(layer "F.SilkS")
		)
		(fp_line
			(start -0.7874 -0.4064)
			(end 0.7874 -0.4064)
			(stroke
				(width 0.1524)
				(type default)
			)
			(layer "F.SilkS")
		)
		(fp_line
			(start 0.67945 0.3048)
			(end 0.120396 0.3048)
			(stroke
				(width 0.1)
				(type default)
			)
			(layer "F.Fab")
		)
		(fp_line
			(start 0.67945 -0.3048)
			(end 0.67945 0.3048)
			(stroke
				(width 0.1)
				(type default)
			)
			(layer "F.Fab")
		)
		(fp_line
			(start 0.12065 -0.2794)
			(end 0.12065 -0.3048)
			(stroke
				(width 0.1)
				(type default)
			)
			(layer "F.Fab")
		)
		(fp_line
			(start 0.12065 -0.3048)
			(end 0.67945 -0.3048)
			(stroke
				(width 0.1)
				(type default)
			)
			(layer "F.Fab")
		)
		(fp_line
			(start 0.120396 0.3048)
			(end 0.120396 0.2794)
			(stroke
				(width 0.1)
				(type default)
			)
			(layer "F.Fab")
		)
		(fp_line
			(start 0.120396 0.2794)
			(end -0.12065 0.2794)
			(stroke
				(width 0.1)
				(type default)
			)
			(layer "F.Fab")
		)
		(fp_line
			(start -0.12065 0.3048)
			(end -0.67945 0.3048)
			(stroke
				(width 0.1)
				(type default)
			)
			(layer "F.Fab")
		)
		(fp_line
			(start -0.12065 0.2794)
			(end -0.12065 0.3048)
			(stroke
				(width 0.1)
				(type default)
			)
			(layer "F.Fab")
		)
		(fp_line
			(start -0.12065 -0.2794)
			(end 0.12065 -0.2794)
			(stroke
				(width 0.1)
				(type default)
			)
			(layer "F.Fab")
		)
		(fp_line
			(start -0.12065 -0.305054)
			(end -0.12065 -0.2794)
			(stroke
				(width 0.1)
				(type default)
			)
			(layer "F.Fab")
		)
		(fp_line
			(start -0.67945 0.3048)
			(end -0.67945 -0.305054)
			(stroke
				(width 0.1)
				(type default)
			)
			(layer "F.Fab")
		)
		(fp_line
			(start -0.67945 -0.305054)
			(end -0.12065 -0.305054)
			(stroke
				(width 0.1)
				(type default)
			)
			(layer "F.Fab")
		)
		(pad "1" smd circle
			(at -0.40005 0 180)
			(size 0 0)
			(layers "F.Cu" "F.Mask" "F.Paste")
			(net "P3V3_AUX")
		)
		(pad "2" smd circle
			(at 0.40005 0 180)
			(size 0 0)
			(layers "F.Cu" "F.Mask" "F.Paste")
			(net "P3V3_OCP_VCC_1")
		)
	)
	(footprint ""
		(layer "F.Cu")
		(at 131.75488 -92.674948 -90)
		(property "Reference" "R4407"
			(at 0 0 270)
			(layer "F.SilkS")
			(hide yes)
			(effects
				(font
					(size 1.27 1.27)
				)
			)
		)
		(property "Value" ""
			(at 0 0 270)
			(layer "F.Fab")
			(effects
				(font
					(size 1.27 1.27)
				)
			)
		)
		(duplicate_pad_numbers_are_jumpers no)
		(fp_line
			(start -0.7874 0.4064)
			(end -0.7874 -0.4064)
			(stroke
				(width 0.1524)
				(type default)
			)
			(layer "F.SilkS")
		)
		(fp_line
			(start 0.7874 0.4064)
			(end -0.7874 0.4064)
			(stroke
				(width 0.1524)
				(type default)
			)
			(layer "F.SilkS")
		)
		(fp_line
			(start -0.7874 -0.4064)
			(end 0.7874 -0.4064)
			(stroke
				(width 0.1524)
				(type default)
			)
			(layer "F.SilkS")
		)
		(fp_line
			(start 0.7874 -0.4064)
			(end 0.7874 0.4064)
			(stroke
				(width 0.1524)
				(type default)
			)
			(layer "F.SilkS")
		)
		(fp_line
			(start -0.67945 0.3048)
			(end -0.67945 -0.305054)
			(stroke
				(width 0.1)
				(type default)
			)
			(layer "F.Fab")
		)
		(fp_line
			(start -0.12065 0.3048)
			(end -0.67945 0.3048)
			(stroke
				(width 0.1)
				(type default)
			)
			(layer "F.Fab")
		)
		(fp_line
			(start 0.120396 0.3048)
			(end 0.120396 0.2794)
			(stroke
				(width 0.1)
				(type default)
			)
			(layer "F.Fab")
		)
		(fp_line
			(start 0.67945 0.3048)
			(end 0.120396 0.3048)
			(stroke
				(width 0.1)
				(type default)
			)
			(layer "F.Fab")
		)
		(fp_line
			(start -0.12065 0.2794)
			(end -0.12065 0.3048)
			(stroke
				(width 0.1)
				(type default)
			)
			(layer "F.Fab")
		)
		(fp_line
			(start 0.120396 0.2794)
			(end -0.12065 0.2794)
			(stroke
				(width 0.1)
				(type default)
			)
			(layer "F.Fab")
		)
		(fp_line
			(start -0.12065 -0.2794)
			(end 0.12065 -0.2794)
			(stroke
				(width 0.1)
				(type default)
			)
			(layer "F.Fab")
		)
		(fp_line
			(start 0.12065 -0.2794)
			(end 0.12065 -0.3048)
			(stroke
				(width 0.1)
				(type default)
			)
			(layer "F.Fab")
		)
		(fp_line
			(start 0.12065 -0.3048)
			(end 0.67945 -0.3048)
			(stroke
				(width 0.1)
				(type default)
			)
			(layer "F.Fab")
		)
		(fp_line
			(start 0.67945 -0.3048)
			(end 0.67945 0.3048)
			(stroke
				(width 0.1)
				(type default)
			)
			(layer "F.Fab")
		)
		(fp_line
			(start -0.67945 -0.305054)
			(end -0.12065 -0.305054)
			(stroke
				(width 0.1)
				(type default)
			)
			(layer "F.Fab")
		)
		(fp_line
			(start -0.12065 -0.305054)
			(end -0.12065 -0.2794)
			(stroke
				(width 0.1)
				(type default)
			)
			(layer "F.Fab")
		)
		(pad "1" smd circle
			(at -0.40005 0 270)
			(size 0 0)
			(layers "F.Cu" "F.Mask" "F.Paste")
			(net "H_CPU0_MEMHOT_OUT_VT_N")
		)
		(pad "2" smd circle
			(at 0.40005 0 270)
			(size 0 0)
			(layers "F.Cu" "F.Mask" "F.Paste")
			(net "H_CPU0_MEMHOT_OUT_LVC1_N")
		)
	)
	(footprint ""
		(layer "F.Cu")
		(at 35.176206 -133.845046 -90)
		(property "Reference" "PR273"
			(at 0 0 270)
			(layer "F.SilkS")
			(hide yes)
			(effects
				(font
					(size 1.27 1.27)
				)
			)
		)
		(property "Value" ""
			(at 0 0 270)
			(layer "F.Fab")
			(effects
				(font
					(size 1.27 1.27)
				)
			)
		)
		(duplicate_pad_numbers_are_jumpers no)
		(fp_line
			(start -0.7874 0.4064)
			(end -0.7874 -0.4064)
			(stroke
				(width 0.1524)
				(type default)
			)
			(layer "F.SilkS")
		)
		(fp_line
			(start 0.7874 0.4064)
			(end -0.7874 0.4064)
			(stroke
				(width 0.1524)
				(type default)
			)
			(layer "F.SilkS")
		)
		(fp_line
			(start -0.7874 -0.4064)
			(end 0.7874 -0.4064)
			(stroke
				(width 0.1524)
				(type default)
			)
			(layer "F.SilkS")
		)
		(fp_line
			(start 0.7874 -0.4064)
			(end 0.7874 0.4064)
			(stroke
				(width 0.1524)
				(type default)
			)
			(layer "F.SilkS")
		)
		(fp_line
			(start -0.67945 0.3048)
			(end -0.67945 -0.305054)
			(stroke
				(width 0.1)
				(type default)
			)
			(layer "F.Fab")
		)
		(fp_line
			(start -0.12065 0.3048)
			(end -0.67945 0.3048)
			(stroke
				(width 0.1)
				(type default)
			)
			(layer "F.Fab")
		)
		(fp_line
			(start 0.120396 0.3048)
			(end 0.120396 0.2794)
			(stroke
				(width 0.1)
				(type default)
			)
			(layer "F.Fab")
		)
		(fp_line
			(start 0.67945 0.3048)
			(end 0.120396 0.3048)
			(stroke
				(width 0.1)
				(type default)
			)
			(layer "F.Fab")
		)
		(fp_line
			(start -0.12065 0.2794)
			(end -0.12065 0.3048)
			(stroke
				(width 0.1)
				(type default)
			)
			(layer "F.Fab")
		)
		(fp_line
			(start 0.120396 0.2794)
			(end -0.12065 0.2794)
			(stroke
				(width 0.1)
				(type default)
			)
			(layer "F.Fab")
		)
		(fp_line
			(start -0.12065 -0.2794)
			(end 0.12065 -0.2794)
			(stroke
				(width 0.1)
				(type default)
			)
			(layer "F.Fab")
		)
		(fp_line
			(start 0.12065 -0.2794)
			(end 0.12065 -0.3048)
			(stroke
				(width 0.1)
				(type default)
			)
			(layer "F.Fab")
		)
		(fp_line
			(start 0.12065 -0.3048)
			(end 0.67945 -0.3048)
			(stroke
				(width 0.1)
				(type default)
			)
			(layer "F.Fab")
		)
		(fp_line
			(start 0.67945 -0.3048)
			(end 0.67945 0.3048)
			(stroke
				(width 0.1)
				(type default)
			)
			(layer "F.Fab")
		)
		(fp_line
			(start -0.67945 -0.305054)
			(end -0.12065 -0.305054)
			(stroke
				(width 0.1)
				(type default)
			)
			(layer "F.Fab")
		)
		(fp_line
			(start -0.12065 -0.305054)
			(end -0.12065 -0.2794)
			(stroke
				(width 0.1)
				(type default)
			)
			(layer "F.Fab")
		)
		(pad "1" smd circle
			(at -0.40005 0 270)
			(size 0 0)
			(layers "F.Cu" "F.Mask" "F.Paste")
			(net "SH_PVCCINFAON_CPU1")
		)
		(pad "2" smd circle
			(at 0.40005 0 270)
			(size 0 0)
			(layers "F.Cu" "F.Mask" "F.Paste")
			(net "SH_PVCCINFAON_CPU1_R")
		)
	)
	(footprint ""
		(layer "F.Cu")
		(at 385.716272 -61.813948)
		(property "Reference" "R764"
			(at 0 0 0)
			(layer "F.SilkS")
			(hide yes)
			(effects
				(font
					(size 1.27 1.27)
				)
			)
		)
		(property "Value" ""
			(at 0 0 0)
			(layer "F.Fab")
			(effects
				(font
					(size 1.27 1.27)
				)
			)
		)
		(duplicate_pad_numbers_are_jumpers no)
		(fp_line
			(start -0.7874 -0.4064)
			(end 0.7874 -0.4064)
			(stroke
				(width 0.1524)
				(type default)
			)
			(layer "F.SilkS")
		)
		(fp_line
			(start -0.7874 0.4064)
			(end -0.7874 -0.4064)
			(stroke
				(width 0.1524)
				(type default)
			)
			(layer "F.SilkS")
		)
		(fp_line
			(start 0.7874 -0.4064)
			(end 0.7874 0.4064)
			(stroke
				(width 0.1524)
				(type default)
			)
			(layer "F.SilkS")
		)
		(fp_line
			(start 0.7874 0.4064)
			(end -0.7874 0.4064)
			(stroke
				(width 0.1524)
				(type default)
			)
			(layer "F.SilkS")
		)
		(fp_line
			(start -0.67945 -0.305054)
			(end -0.12065 -0.305054)
			(stroke
				(width 0.1)
				(type default)
			)
			(layer "F.Fab")
		)
		(fp_line
			(start -0.67945 0.3048)
			(end -0.67945 -0.305054)
			(stroke
				(width 0.1)
				(type default)
			)
			(layer "F.Fab")
		)
		(fp_line
			(start -0.12065 -0.305054)
			(end -0.12065 -0.2794)
			(stroke
				(width 0.1)
				(type default)
			)
			(layer "F.Fab")
		)
		(fp_line
			(start -0.12065 -0.2794)
			(end 0.12065 -0.2794)
			(stroke
				(width 0.1)
				(type default)
			)
			(layer "F.Fab")
		)
		(fp_line
			(start -0.12065 0.2794)
			(end -0.12065 0.3048)
			(stroke
				(width 0.1)
				(type default)
			)
			(layer "F.Fab")
		)
		(fp_line
			(start -0.12065 0.3048)
			(end -0.67945 0.3048)
			(stroke
				(width 0.1)
				(type default)
			)
			(layer "F.Fab")
		)
		(fp_line
			(start 0.120396 0.2794)
			(end -0.12065 0.2794)
			(stroke
				(width 0.1)
				(type default)
			)
			(layer "F.Fab")
		)
		(fp_line
			(start 0.120396 0.3048)
			(end 0.120396 0.2794)
			(stroke
				(width 0.1)
				(type default)
			)
			(layer "F.Fab")
		)
		(fp_line
			(start 0.12065 -0.3048)
			(end 0.67945 -0.3048)
			(stroke
				(width 0.1)
				(type default)
			)
			(layer "F.Fab")
		)
		(fp_line
			(start 0.12065 -0.2794)
			(end 0.12065 -0.3048)
			(stroke
				(width 0.1)
				(type default)
			)
			(layer "F.Fab")
		)
		(fp_line
			(start 0.67945 -0.3048)
			(end 0.67945 0.3048)
			(stroke
				(width 0.1)
				(type default)
			)
			(layer "F.Fab")
		)
		(fp_line
			(start 0.67945 0.3048)
			(end 0.120396 0.3048)
			(stroke
				(width 0.1)
				(type default)
			)
			(layer "F.Fab")
		)
		(pad "1" smd circle
			(at -0.40005 0)
			(size 0 0)
			(layers "F.Cu" "F.Mask" "F.Paste")
			(net "JTAG_DBP_PRDY_N")
		)
		(pad "2" smd circle
			(at 0.40005 0)
			(size 0 0)
			(layers "F.Cu" "F.Mask" "F.Paste")
			(net "JTAG_DBP_PRDY_R1_N")
		)
	)
)
